FILE_TYPE = CONNECTIVITY;
{Allegro Design Entry HDL 16.6-p007 (v16-6-112F) 10/10/2012}
"PAGE_NUMBER" = 113;
0"NC";
1"GND\g";
2"GND\g";
3"GND\g";
4"GND\g";
5"GND\g";
6"P3V3_STBY\g";
7"P3V3_STBY\g";
8"P1V8_MCP_CPU0\g";
9"GND\g";
10"GND\g";
11"GND\g";
12"P1V8_MCP_CPU0\g";
13"P1V8_MCP_CPU1\g";
14"P1V8_MCP_CPU0\g";
15"P1V8_MCP_CPU0\g";
16"GND\g";
17"GND\g";
18"GND\g";
19"P3V3_STBY\g";
20"GND\g";
21"GND\g";
22"GND\g";
23"P3V3_STBY\g";
24"FM_CPU0_CD_PRES";
25"JTAG_MCP_TCK_R";
26"JTAG_MCP_TCK";
27"FM_CPU1_CD_PRES_N";
28"JTAG_MCP_CPU1_TDO";
29"JTAG_MCP_CPU1_TDI";
30"JTAG_MCP_MUX_TDO";
31"JTAG_MCP_TRST_N";
32"JTAG_MCP_TMS";
33"JTAG_MCP_MUX_TDI";
34"JTAG_MCP_TCK_R1";
35"JTAG_MCP_MUX_TDI";
36"JTAG_MCP_TMS";
37"PWRGD_CPU0_G";
38"JTAG_MCP_CPU0_TDO";
39"JTAG_MCP_MUX_TDI";
40"PWRGD_CPU0_G_R";
41"JTAG_MCP_TMS_R";
42"JTAG_MCP_MUX_TDO";
43"TP_JTAG_MCP_IO8_RSVD";
44"JTAG_MCP_TRST_N";
45"JTAG_MCP_MUX_TDO";
46"JTAG_MCP_CPU0_TDI";
47"JTAG_MCP_CPU1_TDI";
48"JTAG_MCP_CPU0_TDO";
49"FM_CPU1_PKGID1";
50"FM_CPU0_AND_CPU1_MCP_PRES";
51"JTAG_MCP_CPU1_TDI";
52"JTAG_MCP_TRST_N";
53"FM_CPU0_OR_CPU1_MCP_PRES";
54"JTAG_MCP_TCK";
55"FM_CPU0_PKGID1";
56"JTAG_MCP_CPU0_TDI";
57"FM_CPU0_OR_CPU1_MCP_PRES";
58"JTAG_MCP_CPU0_TDI_R";
59"JTAG_MCP_TMS_R1";
60"JTAG_MCP_TMS";
61"JTAG_MCP_CPU1_TDI_R";
%"NC7SB3157"
"1","(-2075,3525)","2","mstr_analog","I107";
;
CDS_SEC"1"
CDS_LOCATION"U1M2"
PACK_TYPE"SMLF"
PART_NUMBER"C99406-001"
MATERIAL"IC"
LOCATION"U1M2"
GROUP"MCP"
CDS_LIB"mstr_analog"
ROOM"DEBUG"
SEC"1"
SEC_TYPE"SMLF"
BOM_COST"DEBUG";
"GND"
$PN"2"1;
"A"
$PN"4"45;
"VCC"
$PN"5"6;
"B1"
$PN"1"38;
"B0"
$PN"3"28;
"S"
$PN"6"27;
%"GND"
"1","(-2500,3225)","0","mstr_symbols","I109";
;
HDL_POWER"GND"
BODY_TYPE"PLUMBING"
CDS_LIB"mstr_symbols"
VOLTAGE"0.0V"
SIZE"1B";
"A\NAC"1;
%"GND"
"1","(-1150,4200)","0","mstr_symbols","I110";
;
HDL_POWER"GND"
BODY_TYPE"PLUMBING"
SIZE"1B"
VOLTAGE"0.0V"
CDS_LIB"mstr_symbols";
"A\NAC"2;
%"CAP_A"
"1","(-1550,3025)","2","dev_discrete","I116";
;
CDS_LOCATION"C1M31"
LOCATION"C1M31"
VALUE"0.01UF"
VOLTAGE"25V"
TOLERANCE"10%"
MATERIAL"X7R"
GROUP"MCP"
PACK_TYPE"0402V"
PART_NUMBER"A36096-045"
CDS_LIB"dev_discrete"
CDS_SEC"1"
BOM_COST"DEBUG"
ROOM"DEBUG"
SEC"1"
SEC_TYPE"0402V";
"B"
$PN"2"3;
"A"
$PN"1"6;
%"CAP_A"
"1","(-1250,3025)","2","dev_discrete","I117";
;
CDS_LOCATION"C1M32"
PACK_TYPE"0402V"
VALUE"1.0UF"
GROUP"MCP"
VOLTAGE"6.3V"
LOCATION"C1M32"
TOLERANCE"10%"
MATERIAL"X6S"
PART_NUMBER"D97712-004"
CDS_LIB"dev_discrete"
ROOM"DEBUG"
SEC"1"
SEC_TYPE"0402V"
CDS_SEC"1"
BOM_COST"DEBUG";
"B"
$PN"2"3;
"A"
$PN"1"6;
%"GND"
"1","(-1250,2725)","0","mstr_symbols","I118";
;
HDL_POWER"GND"
BODY_TYPE"PLUMBING"
BOM_COST"DEBUG"
ROOM"DEBUG"
VOLTAGE"0.0V"
SIZE"1B"
CDS_LIB"mstr_symbols";
"A\NAC"3;
%"CAP_A"
"1","(-2250,1250)","2","dev_discrete","I119";
;
CDS_LOCATION"C1M28"
VOLTAGE"25V"
VALUE"0.01UF"
LOCATION"C1M28"
GROUP"MCP"
PART_NUMBER"A36096-045"
MATERIAL"X7R"
PACK_TYPE"0402V"
TOLERANCE"10%"
CDS_LIB"dev_discrete"
ROOM"DEBUG"
CDS_SEC"1"
BOM_COST"DEBUG"
SEC"1"
SEC_TYPE"0402V";
"B"
$PN"2"4;
"A"
$PN"1"7;
%"GND"
"1","(-2250,1050)","0","mstr_symbols","I121";
;
HDL_POWER"GND"
BODY_TYPE"PLUMBING"
VOLTAGE"0.0V"
SIZE"1B"
ROOM"DEBUG"
BOM_COST"DEBUG"
CDS_LIB"mstr_symbols";
"A\NAC"4;
%"74CBTLV1G125"
"1","(-1500,850)","0","mstr_ttl","I127";
;
CDS_SEC"1"
CDS_LOCATION"U1M6"
POWER_GROUP"VCC=P3V3_STBY;GND=GND;"
LOCATION"U1M6"
GROUP"MCP"
PACK_TYPE"SMLF"
PART_NUMBER"C88177-001"
MATERIAL"IC"
CDS_LIB"mstr_ttl"
ROOM"DEBUG"
SEC"1"
SEC_TYPE"SMLF"
BOM_COST"DEBUG";
"OE_N \B"
$PN"1"50;
"B"
$PN"4"51;
"A"
$PN"2"48;
%"GND"
"1","(-975,4450)","0","mstr_symbols","I146";
;
HDL_POWER"GND"
BODY_TYPE"PLUMBING"
ROOM"DEBUG"
BOM_COST"DEBUG"
VOLTAGE"0.0V"
SIZE"1B"
CDS_LIB"mstr_symbols";
"A\NAC"5;
%"CAP_A"
"1","(-975,4650)","0","dev_discrete","I147";
;
CDS_LOCATION"C1M29"
PART_NUMBER"A36096-030"
PACK_TYPE"0402V"
MATERIAL"X7R"
TOLERANCE"10%"
VOLTAGE"16V"
VALUE"0.1UF"
LOCATION"C1M29"
GROUP"MCP"
CDS_LIB"dev_discrete"
$SEC"1"
CDS_SEC"1"
ROOM"DEBUG";
"B"
$PN"2"5;
"A"
$PN"1"8;
%"P3V3_STBY"
"1","(-1250,3300)","0","mstr_symbols","I160";
;
HDL_POWER"P3V3_STBY"
BODY_TYPE"PLUMBING"
VOLTAGE"3.3V"
SIZE"1B"
CDS_LIB"mstr_symbols";
"G\NAC"6;
%"P3V3_STBY"
"1","(-2250,1450)","0","mstr_symbols","I161";
;
HDL_POWER"P3V3_STBY"
BODY_TYPE"PLUMBING"
VOLTAGE"3.3V"
CDS_LIB"mstr_symbols"
SIZE"1B";
"G\NAC"7;
%"RES"
"1","(-2600,4150)","0","mstr_discrete","I168";
;
CDS_SEC"1"
CDS_LOCATION"R9B14"
VALUE"1.00K"
TOLERANCE"1%"
MATERIAL"CHIP"
LOCATION"R9B14"
WATTAGE"1/16W"
PART_NUMBER"G21796-026"
PACK_TYPE"0402"
GROUP"MCP"
CDS_LIB"mstr_discrete"
SEC"1"
SEC_TYPE"0402"
ROOM"DEBUG";
"B"
$PN"2"40;
"A"
$PN"1"37;
%"VCC_CORE"
"1","(-1100,4900)","0","mstr_symbols","I171";
;
HDL_POWER"P1V8_MCP_CPU0"
CDS_LIB"mstr_symbols";
"A"8;
%"SCONN10_C12536004"
"1","(-1375,4375)","0","mstr_sconn","I175";
;
CDS_SEC"1"
CDS_LOCATION"J9B4"
PART_NUMBER"C12536-004"
MATERIAL"CONN"
GROUP"MCP"
LOCATION"J9B4"
ROOM"DEBUG"
SEC"1"
SEC_TYPE"SMLF"
PACK_TYPE"SMLF"
CDS_LIB"mstr_sconn";
"IO1"
$PN"1"25;
"IO10"
$PN"10"2;
"IO3"
$PN"3"42;
"IO5"
$PN"5"41;
"IO7"
$PN"7"40;
"IO9"
$PN"9"39;
"IO2"
$PN"2"2;
"IO4"
$PN"4"8;
"IO6"
$PN"6"44;
"IO8"
$PN"8"43;
%"RES"
"2","(2600,4150)","2","mstr_discrete","I179";
;
CDS_SEC"1"
CDS_LOCATION"R9B9"
TOLERANCE"1%"
GROUP"MCP"
PACK_TYPE"0402"
PART_NUMBER"G21796-026"
LOCATION"R9B9"
VALUE"1.00K"
MATERIAL"CHIP"
WATTAGE"1/16W"
SEC"1"
SEC_TYPE"0402"
CDS_LIB"mstr_discrete";
"A"
$PN"1"54;
"B"
$PN"2"9;
%"RES"
"1","(2800,4400)","0","mstr_discrete","I180";
;
CDS_SEC"1"
CDS_LOCATION"R9B10"
POP"NOPOP"
PART_NUMBER"G21796-047"
LOCATION"R9B10"
PACK_TYPE"0402"
MATERIAL"CHIP"
WATTAGE"1/16W"
VALUE"49.9"
TOLERANCE"1%"
CDS_LIB"mstr_discrete"
ROOM"DEBUG"
SEC"1"
SEC_TYPE"0402"
BOM_COST"DEBUG";
"B"
$PN"2"34;
"A"
$PN"1"54;
%"GND"
"1","(2600,3950)","0","mstr_symbols","I182";
;
HDL_POWER"GND"
BODY_TYPE"PLUMBING"
VOLTAGE"0.0V"
SIZE"1B"
CDS_LIB"mstr_symbols";
"A\NAC"9;
%"74CBTLV1G125"
"1","(3650,4400)","0","mstr_ttl","I185";
;
CDS_SEC"1"
CDS_LOCATION"U9A5"
MATERIAL"IC"
POWER_GROUP"VCC=P3V3_STBY;GND=GND;"
POP"NOPOP"
PACK_TYPE"SMLF"
LOCATION"U9A5"
PART_NUMBER"C88177-001"
SEC"1"
BOM_COST"DEBUG"
SEC_TYPE"SMLF"
ROOM"DEBUG"
CDS_LIB"mstr_ttl";
"OE_N \B"
$PN"1"53;
"B"
$PN"4"10;
"A"
$PN"2"34;
%"GND"
"1","(3950,4300)","0","mstr_symbols","I186";
;
HDL_POWER"GND"
BODY_TYPE"PLUMBING"
SIZE"1B"
CDS_LIB"mstr_symbols"
VOLTAGE"0.0V";
"A\NAC"10;
%"74CBTLV1G125"
"1","(1600,2000)","0","mstr_ttl","I190";
;
CDS_SEC"1"
CDS_LOCATION"U6M1"
POWER_GROUP"VCC=P3V3_STBY;GND=GND;"
POP"NOPOP"
PART_NUMBER"C88177-001"
MATERIAL"IC"
PACK_TYPE"SMLF"
LOCATION"U6M1"
SEC_TYPE"SMLF"
SEC"1"
BOM_COST"DEBUG"
ROOM"DEBUG"
CDS_LIB"mstr_ttl";
"OE_N \B"
$PN"1"49;
"B"
$PN"4"61;
"A"
$PN"2"13;
%"RES"
"2","(2450,2650)","2","mstr_discrete","I195";
;
CDS_SEC"1"
CDS_LOCATION"R1M22"
LOCATION"R1M22"
VALUE"49.9"
TOLERANCE"1%"
PACK_TYPE"0402"
PART_NUMBER"G21796-047"
MATERIAL"CHIP"
WATTAGE"1/16W"
POP"NOPOP"
CDS_LIB"mstr_discrete"
ROOM"DEBUG"
SEC"1"
SEC_TYPE"0402";
"A"
$PN"1"59;
"B"
$PN"2"60;
%"74CBTLV1G125"
"1","(1600,2825)","0","mstr_ttl","I196";
;
CDS_SEC"1"
CDS_LOCATION"U1M5"
POWER_GROUP"VCC=P3V3_STBY;GND=GND;"
MATERIAL"IC"
POP"NOPOP"
PART_NUMBER"C88177-001"
LOCATION"U1M5"
PACK_TYPE"SMLF"
CDS_LIB"mstr_ttl"
SEC_TYPE"SMLF"
BOM_COST"DEBUG"
SEC"1"
ROOM"DEBUG";
"OE_N \B"
$PN"1"57;
"B"
$PN"4"59;
"A"
$PN"2"15;
%"RES"
"2","(1400,4225)","0","mstr_discrete","I199";
;
CDS_SEC"1"
CDS_LOCATION"R1M23"
PART_NUMBER"G21796-026"
PACK_TYPE"0402"
MATERIAL"EMPTY"
LOCATION"R1M23"
WATTAGE"1/16W"
VALUE"1.00K"
TOLERANCE"1%"
CDS_LIB"mstr_discrete"
ROOM"DEBUG"
SEC"1"
SEC_TYPE"0402"
BOM_COST"DEBUG";
"A"
$PN"1"52;
"B"
$PN"2"11;
%"GND"
"1","(1400,3950)","0","mstr_symbols","I200";
;
HDL_POWER"GND"
BODY_TYPE"PLUMBING"
CDS_LIB"mstr_symbols"
VOLTAGE"0.0V"
SIZE"1B";
"A\NAC"11;
%"VCC_CORE"
"1","(3575,1275)","0","mstr_symbols","I201";
;
HDL_POWER"P1V8_MCP_CPU0"
CDS_LIB"mstr_symbols";
"A"12;
%"RES"
"2","(3175,1025)","0","mstr_discrete","I202";
;
CDS_SEC"1"
CDS_LOCATION"R1M19"
LOCATION"R1M19"
WATTAGE"1/16W"
MATERIAL"CHIP"
VALUE"1.00K"
PACK_TYPE"0402"
TOLERANCE"1%"
GROUP"MCP"
PART_NUMBER"G21796-026"
SEC"1"
BOM_COST"DEBUG"
SEC_TYPE"0402"
ROOM"DEBUG"
CDS_LIB"mstr_discrete";
"A"
$PN"1"12;
"B"
$PN"2"32;
%"RES"
"2","(3425,1025)","0","mstr_discrete","I203";
;
CDS_SEC"1"
CDS_LOCATION"R9B12"
LOCATION"R9B12"
PART_NUMBER"G21796-026"
PACK_TYPE"0402"
GROUP"MCP"
WATTAGE"1/16W"
MATERIAL"CHIP"
TOLERANCE"1%"
VALUE"1.00K"
ROOM"DEBUG"
SEC"1"
SEC_TYPE"0402"
BOM_COST"DEBUG"
CDS_LIB"mstr_discrete";
"A"
$PN"1"12;
"B"
$PN"2"30;
%"RES"
"2","(2925,1025)","0","mstr_discrete","I204";
;
CDS_SEC"1"
CDS_LOCATION"R1M20"
PART_NUMBER"G21796-026"
PACK_TYPE"0402"
POP"NOPOP"
WATTAGE"1/16W"
MATERIAL"CHIP"
LOCATION"R1M20"
VALUE"1.00K"
TOLERANCE"1%"
ROOM"DEBUG"
SEC"1"
SEC_TYPE"0402"
BOM_COST"DEBUG"
CDS_LIB"mstr_discrete";
"A"
$PN"1"12;
"B"
$PN"2"33;
%"RES"
"2","(3675,1025)","0","mstr_discrete","I205";
;
CDS_SEC"1"
CDS_LOCATION"R1M21"
LOCATION"R1M21"
WATTAGE"1/16W"
GROUP"MCP"
MATERIAL"CHIP"
PART_NUMBER"G21796-026"
VALUE"1.00K"
TOLERANCE"1%"
PACK_TYPE"0402"
BOM_COST"DEBUG"
SEC_TYPE"0402"
SEC"1"
ROOM"DEBUG"
CDS_LIB"mstr_discrete";
"A"
$PN"1"12;
"B"
$PN"2"31;
%"74CBTLV1G125"
"1","(1625,3375)","0","mstr_ttl","I206";
;
CDS_SEC"1"
CDS_LOCATION"U4R1"
LOCATION"U4R1"
POWER_GROUP"VCC=P3V3_STBY;GND=GND;"
POP"NOPOP"
PART_NUMBER"C88177-001"
PACK_TYPE"SMLF"
MATERIAL"IC"
SEC_TYPE"SMLF"
BOM_COST"DEBUG"
SEC"1"
ROOM"DEBUG"
CDS_LIB"mstr_ttl";
"OE_N \B"
$PN"1"55;
"B"
$PN"4"58;
"A"
$PN"2"14;
%"VCC_CORE"
"1","(900,2100)","0","mstr_symbols","I236";
;
HDL_POWER"P1V8_MCP_CPU1"
VOLTAGE"1.8"
CDS_LIB"mstr_symbols";
"A"13;
%"RES"
"1","(-2600,4625)","0","mstr_discrete","I239";
;
CDS_SEC"1"
CDS_LOCATION"R9B11"
LOCATION"R9B11"
PACK_TYPE"0402"
MATERIAL"CHIP"
VALUE"0.0"
TOLERANCE"5%"
WATTAGE"1/16W"
PART_NUMBER"G21497-005"
GROUP"MCP"
SEC_TYPE"0402"
CDS_LIB"mstr_discrete"
SEC"1";
"B"
$PN"2"25;
"A"
$PN"1"26;
%"RES"
"1","(-2600,4375)","0","mstr_discrete","I240";
;
CDS_SEC"1"
CDS_LOCATION"R9B13"
VALUE"0.0"
TOLERANCE"5%"
PACK_TYPE"0402"
WATTAGE"1/16W"
MATERIAL"CHIP"
PART_NUMBER"G21497-005"
GROUP"MCP"
LOCATION"R9B13"
CDS_LIB"mstr_discrete"
SEC"1"
SEC_TYPE"0402";
"B"
$PN"2"41;
"A"
$PN"1"36;
%"VCC_CORE"
"1","(900,3475)","0","mstr_symbols","I241";
;
HDL_POWER"P1V8_MCP_CPU0"
CDS_LIB"mstr_symbols";
"A"14;
%"VCC_CORE"
"1","(1150,2925)","0","mstr_symbols","I245";
;
HDL_POWER"P1V8_MCP_CPU0"
CDS_LIB"mstr_symbols";
"A"15;
%"CAP_A"
"1","(2125,3200)","2","dev_discrete","I246";
;
CDS_LOCATION"C4R2"
VALUE"0.1UF"
LOCATION"C4R2"
PACK_TYPE"0402V"
VOLTAGE"16V"
POP"NOPOP"
MATERIAL"X7R"
TOLERANCE"10%"
PART_NUMBER"A36096-030"
CDS_LIB"dev_discrete"
ROOM"DEBUG"
CDS_SEC"1"
SEC_TYPE"0402V"
SEC"1";
"B"
$PN"2"16;
"A"
$PN"1"58;
%"GND"
"1","(2125,3000)","0","mstr_symbols","I247";
;
HDL_POWER"GND"
BODY_TYPE"PLUMBING"
CDS_LIB"mstr_symbols"
VOLTAGE"0.0V"
SIZE"1B";
"A\NAC"16;
%"CAP_A"
"1","(2125,2650)","2","dev_discrete","I248";
;
CDS_LOCATION"C1M33"
VOLTAGE"16V"
TOLERANCE"10%"
MATERIAL"X7R"
LOCATION"C1M33"
VALUE"0.1UF"
POP"NOPOP"
PACK_TYPE"0402V"
PART_NUMBER"A36096-030"
CDS_LIB"dev_discrete"
CDS_SEC"1"
ROOM"DEBUG"
BOM_COST"DEBUG"
SEC_TYPE"0402V"
SEC"1";
"B"
$PN"2"17;
"A"
$PN"1"59;
%"GND"
"1","(2125,2450)","0","mstr_symbols","I249";
;
HDL_POWER"GND"
BODY_TYPE"PLUMBING"
ROOM"DEBUG"
BOM_COST"DEBUG"
VOLTAGE"0.0V"
CDS_LIB"mstr_symbols"
SIZE"1B";
"A\NAC"17;
%"CAP_A"
"1","(2150,1825)","2","dev_discrete","I250";
;
CDS_LOCATION"C6M6"
PART_NUMBER"A36096-030"
MATERIAL"X7R"
TOLERANCE"10%"
POP"NOPOP"
PACK_TYPE"0402V"
VALUE"0.1UF"
LOCATION"C6M6"
VOLTAGE"16V"
CDS_LIB"dev_discrete"
SEC"1"
CDS_SEC"1"
BOM_COST"DEBUG"
ROOM"DEBUG"
SEC_TYPE"0402V";
"B"
$PN"2"18;
"A"
$PN"1"61;
%"GND"
"1","(2150,1600)","0","mstr_symbols","I251";
;
HDL_POWER"GND"
BODY_TYPE"PLUMBING"
ROOM"DEBUG"
BOM_COST"DEBUG"
VOLTAGE"0.0V"
CDS_LIB"mstr_symbols"
SIZE"1B";
"A\NAC"18;
%"NC7SB3157"
"1","(-2125,2325)","2","mstr_analog","I255";
;
CDS_SEC"1"
CDS_LOCATION"U2M1"
PACK_TYPE"SMLF"
GROUP"MCP"
MATERIAL"IC"
PART_NUMBER"C99406-001"
LOCATION"U2M1"
CDS_LIB"mstr_analog"
BOM_COST"DEBUG"
SEC_TYPE"SMLF"
SEC"1"
ROOM"DEBUG";
"GND"
$PN"2"21;
"A"
$PN"4"35;
"VCC"
$PN"5"19;
"B1"
$PN"1"46;
"B0"
$PN"3"47;
"S"
$PN"6"24;
%"P3V3_STBY"
"1","(-1275,2100)","0","mstr_symbols","I259";
;
HDL_POWER"P3V3_STBY"
BODY_TYPE"PLUMBING"
VOLTAGE"3.3V"
SIZE"1B"
CDS_LIB"mstr_symbols";
"G\NAC"19;
%"GND"
"1","(-1275,1500)","0","mstr_symbols","I261";
;
HDL_POWER"GND"
BODY_TYPE"PLUMBING"
ROOM"DEBUG"
BOM_COST"DEBUG"
SIZE"1B"
VOLTAGE"0.0V"
CDS_LIB"mstr_symbols";
"A\NAC"20;
%"GND"
"1","(-2550,2025)","0","mstr_symbols","I263";
;
HDL_POWER"GND"
BODY_TYPE"PLUMBING"
VOLTAGE"0.0V"
SIZE"1B"
CDS_LIB"mstr_symbols";
"A\NAC"21;
%"CAP_A"
"1","(-1275,1825)","2","dev_discrete","I265";
;
CDS_LOCATION"C1M34"
GROUP"MCP"
PACK_TYPE"0402V"
PART_NUMBER"A36096-045"
MATERIAL"X7R"
VOLTAGE"25V"
TOLERANCE"10%"
LOCATION"C1M34"
VALUE"0.01UF"
BOM_COST"DEBUG"
CDS_SEC"1"
ROOM"DEBUG"
CDS_LIB"dev_discrete"
SEC"1"
SEC_TYPE"0402V";
"B"
$PN"2"20;
"A"
$PN"1"19;
%"CAP_A"
"1","(-1600,1825)","2","dev_discrete","I266";
;
CDS_LOCATION"C1M35"
GROUP"MCP"
VOLTAGE"25V"
LOCATION"C1M35"
VALUE"0.01UF"
TOLERANCE"10%"
PACK_TYPE"0402V"
PART_NUMBER"A36096-045"
MATERIAL"X7R"
CDS_LIB"dev_discrete"
BOM_COST"DEBUG"
CDS_SEC"1"
ROOM"DEBUG"
SEC"1"
SEC_TYPE"0402V";
"B"
$PN"2"20;
"A"
$PN"1"19;
%"CAP_A"
"1","(3025,3650)","2","dev_discrete","I267";
;
CDS_LOCATION"C1L20"
GROUP"MCP"
VOLTAGE"25V"
TOLERANCE"10%"
LOCATION"C1L20"
VALUE"0.01UF"
PACK_TYPE"0402V"
MATERIAL"X7R"
PART_NUMBER"A36096-045"
SEC_TYPE"0402V"
SEC"1"
BOM_COST"DEBUG"
CDS_SEC"1"
ROOM"DEBUG"
CDS_LIB"dev_discrete";
"B"
$PN"2"22;
"A"
$PN"1"23;
%"GND"
"1","(3025,3450)","0","mstr_symbols","I268";
;
HDL_POWER"GND"
BODY_TYPE"PLUMBING"
SIZE"1B"
CDS_LIB"mstr_symbols"
VOLTAGE"0.0V"
BOM_COST"DEBUG"
ROOM"DEBUG";
"A\NAC"22;
%"P3V3_STBY"
"1","(3025,3850)","0","mstr_symbols","I269";
;
HDL_POWER"P3V3_STBY"
BODY_TYPE"PLUMBING"
SIZE"1B"
CDS_LIB"mstr_symbols"
VOLTAGE"3.3V";
"G\NAC"23;
%"RES"
"2","(2450,3200)","0","mstr_discrete","I270";
;
CDS_SEC"1"
CDS_LOCATION"R4R6"
GROUP"MCP"
LOCATION"R4R6"
PACK_TYPE"0402"
PART_NUMBER"G21796-026"
TOLERANCE"1%"
VALUE"1.00K"
MATERIAL"CHIP"
WATTAGE"1/16W"
SEC"1"
SEC_TYPE"0402"
ROOM"PROC_SIDEBAND"
CDS_LIB"mstr_discrete";
"A"
$PN"1"58;
"B"
$PN"2"56;
%"RES"
"2","(2450,1825)","0","mstr_discrete","I271";
;
CDS_SEC"1"
CDS_LOCATION"R6M8"
GROUP"MCP"
PACK_TYPE"0402"
MATERIAL"CHIP"
PART_NUMBER"G21796-026"
VALUE"1.00K"
TOLERANCE"1%"
WATTAGE"1/16W"
LOCATION"R6M8"
SEC"1"
SEC_TYPE"0402"
ROOM"PROC_SIDEBAND"
CDS_LIB"mstr_discrete";
"A"
$PN"1"61;
"B"
$PN"2"29;
%"RES"
"1","(1600,3750)","0","mstr_discrete","I272";
;
CDS_SEC"1"
CDS_LOCATION"R5W1"
PART_NUMBER"G21497-005"
VALUE"0.0"
LOCATION"R5W1"
WATTAGE"1/16W"
MATERIAL"CHIP"
PACK_TYPE"0402"
TOLERANCE"5%"
GROUP"MCP"
CDS_LIB"mstr_discrete"
SEC"1"
SEC_TYPE"0402";
"B"
$PN"2"58;
"A"
$PN"1"14;
%"RES"
"1","(1600,2375)","0","mstr_discrete","I273";
;
CDS_SEC"1"
$SEC"1"
CDS_LOCATION"R5W2"
LOCATION"R5W2"
MATERIAL"CHIP"
PART_NUMBER"G21497-005"
WATTAGE"1/16W"
PACK_TYPE"0402"
TOLERANCE"5%"
VALUE"0.0"
GROUP"MCP"
CDS_LIB"mstr_discrete";
"B"
$PN"2"61;
"A"
$PN"1"13;
END.
